#ISCELL
  mstr_misc dns *
  *
#ISCELL
  mstr_symbols design_note *
  *
#ISCELL
  mstr_symbols intel_corp_bpage *
  *
#ISCELL
  mstr_standard offpage *
  page226_i1
#ISCELL
  mstr_standard offpage *
  page226_i10
#ISCELL
  mstr_standard offpage *
  page226_i11
#CELL
  mstr_discrete res *
  page226_i13
#CELL
  mstr_discrete res *
  page226_i14
#ISCELL
  mstr_symbols p3v3_stby *
  page226_i15
#CELL
  mstr_discrete res *
  page226_i16
#CELL
  mstr_discrete res *
  page226_i17
#ISCELL
  mstr_standard offpage *
  page226_i18
#ISCELL
  mstr_standard offpage *
  page226_i19
#ISCELL
  mstr_standard offpage *
  page226_i2
#ISCELL
  mstr_standard offpage *
  page226_i20
#CELL
  mstr_discrete res *
  page226_i21
#CELL
  mstr_discrete res *
  page226_i22
#CELL
  mstr_discrete res *
  page226_i23
#ISCELL
  mstr_symbols gnd *
  page226_i24
#CELL
  dev_discrete cap_a *
  page226_i25
#ISCELL
  mstr_symbols gnd *
  page226_i26
#CELL
  dev_discrete cap_a *
  page226_i27
#ISCELL
  mstr_symbols gnd *
  page226_i28
#ISCELL
  mstr_symbols p3v3_stby *
  page226_i29
#CELL
  mstr_discrete res *
  page226_i30
#CELL
  mstr_discrete res *
  page226_i32
#ISCELL
  mstr_standard offpage *
  page226_i34
#ISCELL
  mstr_symbols gnd *
  page226_i35
#CELL
  mstr_discrete cap *
  page226_i36
#CELL
  mstr_discrete cap *
  page226_i39
#ISCELL
  mstr_standard offpage *
  page226_i4
#ISCELL
  mstr_standard offpage *
  page226_i40
#CELL
  dev_discrete cap_a *
  page226_i41
#ISCELL
  mstr_symbols gnd *
  page226_i42
#ISCELL
  mstr_symbols gnd *
  page226_i43
#CELL
  dev_discrete cap_a *
  page226_i44
#ISCELL
  mstr_standard offpage *
  page226_i45
#ISCELL
  mstr_symbols gnd *
  page226_i46
#ISCELL
  mstr_symbols gnd *
  page226_i47
#ISCELL
  mstr_symbols gnd *
  page226_i48
#ISCELL
  mstr_symbols pvccio_cpu1 *
  page226_i49
#CELL
  mstr_discrete res *
  page226_i50
#CELL
  mstr_discrete res *
  page226_i53
#ISCELL
  mstr_symbols vcc_core *
  page226_i56
#CELL
  mstr_discrete res *
  page226_i57
#CELL
  mstr_discrete res *
  page226_i58
#CELL
  mstr_discrete cap *
  page226_i59
#ISCELL
  mstr_symbols gnd *
  page226_i60
#ISCELL
  mstr_symbols gnd *
  page226_i61
#ISCELL
  mstr_standard offpage *
  page226_i62
#ISCELL
  mstr_standard offpage *
  page226_i63
#ISCELL
  mstr_standard offpage *
  page226_i64
#ISCELL
  mstr_standard offpage *
  page226_i65
#ISCELL
  mstr_standard offpage *
  page226_i67
#ISCELL
  mstr_standard offpage *
  page226_i68
#ISCELL
  mstr_symbols pvccio_cpu1 *
  page226_i7
#ISCELL
  mstr_standard offpage *
  page226_i70
#ISCELL
  mstr_standard offpage *
  page226_i71
#ISCELL
  mstr_standard offpage *
  page226_i72
#ISCELL
  mstr_standard offpage *
  page226_i74
#CELL
  mstr_discrete res *
  page226_i77
#CELL
  mstr_discrete res *
  page226_i78
#CELL
  mstr_discrete res *
  page226_i79
#CELL
  mstr_discrete res *
  page226_i8
#CELL
  mstr_discrete cap *
  page226_i80
#ISCELL
  mstr_symbols gnd *
  page226_i81
#CELL
  mstr_discrete res *
  page226_i82
#CELL
  mstr_discrete res *
  page226_i84
#CELL
  mstr_discrete res *
  page226_i85
#CELL
  mstr_discrete res *
  page226_i87
#CELL
  mstr_discrete res *
  page226_i88
#ISCELL
  mstr_standard offpage *
  page226_i89
#ISCELL
  mstr_standard offpage *
  page226_i9
#CELL
  mstr_controller pxm1310b *
  page226_i90
#ISCELL
  mstr_symbols gnd *
  page226_i91
#CELL
  dev_discrete cap_a *
  page226_i92
